# T6G (Grand Teton) — schematic netlist excerpt (pin names and nets, part order shuffled) for the footprints in the layout excerpt that follows; sources: Cadence DE-HDL packaged netlist, KiCad conversion of 04192023_DAF0TMB3IC0_F0TG_MB_C_brd_V02_OCP.brd

R1799  Q_RES  7.87K 1% CHIP  pkg 0402LF  page 257 : A = P12V_AUX ; B = P12V_AUX_ADC

(kicad_pcb
	(version 20260206)
	(generator "pcbnew")
	(generator_version "10.0")
	(general
		(thickness 1.6)
		(legacy_teardrops no)
	)
	(paper "A4")
	(title_block
		(title "04192023_DAF0TMB3IC0_F0TG_MB_C_brd_V02_OCP.brd")
		(comment 1 "Grand Teton / footprints 3759-3759 of 8354")
	)
	(layers
		(0 "F.Cu" signal "TOP")
		(4 "In1.Cu" signal "GND")
		(6 "In2.Cu" signal "IN1")
		(8 "In3.Cu" signal "GND1")
		(10 "In4.Cu" signal "IN2")
		(12 "In5.Cu" signal "GND2")
		(14 "In6.Cu" signal "IN3")
		(16 "In7.Cu" signal "GND3")
		(18 "In8.Cu" signal "VCC")
		(20 "In9.Cu" signal "VCC1")
		(22 "In10.Cu" signal "GND4")
		(24 "In11.Cu" signal "IN4")
		(26 "In12.Cu" signal "GND5")
		(28 "In13.Cu" signal "IN5")
		(30 "In14.Cu" signal "GND6")
		(32 "In15.Cu" signal "IN6")
		(34 "In16.Cu" signal "GND7")
		(2 "B.Cu" signal "BOTTOM")
		(9 "F.Adhes" user "F.Adhesive")
		(11 "B.Adhes" user "B.Adhesive")
		(13 "F.Paste" user "Package Geometry/Pastemask Top")
		(15 "B.Paste" user "Package Geometry/Pastemask Bottom")
		(5 "F.SilkS" user "Ref Des/Silkscreen Top")
		(7 "B.SilkS" user "Ref Des/Silkscreen Bottom")
		(1 "F.Mask" user "Board Geometry/Soldermask Top")
		(3 "B.Mask" user "Board Geometry/Soldermask Bottom")
		(17 "Dwgs.User" user "User.Drawings")
		(19 "Cmts.User" user "User.Comments")
		(21 "Eco1.User" user "User.Eco1")
		(23 "Eco2.User" user "User.Eco2")
		(25 "Edge.Cuts" user "Board Geometry/Outline")
		(27 "Margin" user)
		(31 "F.CrtYd" user "Package Geometry/Place Bound Top")
		(29 "B.CrtYd" user "Package Geometry/Place Bound Bottom")
		(35 "F.Fab" user "Ref Des/Assembly Top")
		(33 "B.Fab" user "Ref Des/Assembly Bottom")
	)
	(footprint ""
		(layer "F.Cu")
		(at 329.592178 -46.748954 180)
		(property "Reference" "R1799"
			(at 0 0 180)
			(layer "F.SilkS")
			(hide yes)
			(effects
				(font
					(size 1.27 1.27)
				)
			)
		)
		(property "Value" ""
			(at 0 0 180)
			(layer "F.Fab")
			(effects
				(font
					(size 1.27 1.27)
				)
			)
		)
		(duplicate_pad_numbers_are_jumpers no)
		(fp_line
			(start 0.7874 0.4064)
			(end -0.7874 0.4064)
			(stroke
				(width 0.1524)
				(type default)
			)
			(layer "F.SilkS")
		)
		(fp_line
			(start 0.7874 -0.4064)
			(end 0.7874 0.4064)
			(stroke
				(width 0.1524)
				(type default)
			)
			(layer "F.SilkS")
		)
		(fp_line
			(start -0.7874 0.4064)
			(end -0.7874 -0.4064)
			(stroke
				(width 0.1524)
				(type default)
			)
			(layer "F.SilkS")
		)
		(fp_line
			(start -0.7874 -0.4064)
			(end 0.7874 -0.4064)
			(stroke
				(width 0.1524)
				(type default)
			)
			(layer "F.SilkS")
		)
		(fp_line
			(start 0.67945 0.3048)
			(end 0.120396 0.3048)
			(stroke
				(width 0.1)
				(type default)
			)
			(layer "F.Fab")
		)
		(fp_line
			(start 0.67945 -0.3048)
			(end 0.67945 0.3048)
			(stroke
				(width 0.1)
				(type default)
			)
			(layer "F.Fab")
		)
		(fp_line
			(start 0.12065 -0.2794)
			(end 0.12065 -0.3048)
			(stroke
				(width 0.1)
				(type default)
			)
			(layer "F.Fab")
		)
		(fp_line
			(start 0.12065 -0.3048)
			(end 0.67945 -0.3048)
			(stroke
				(width 0.1)
				(type default)
			)
			(layer "F.Fab")
		)
		(fp_line
			(start 0.120396 0.3048)
			(end 0.120396 0.2794)
			(stroke
				(width 0.1)
				(type default)
			)
			(layer "F.Fab")
		)
		(fp_line
			(start 0.120396 0.2794)
			(end -0.12065 0.2794)
			(stroke
				(width 0.1)
				(type default)
			)
			(layer "F.Fab")
		)
		(fp_line
			(start -0.12065 0.3048)
			(end -0.67945 0.3048)
			(stroke
				(width 0.1)
				(type default)
			)
			(layer "F.Fab")
		)
		(fp_line
			(start -0.12065 0.2794)
			(end -0.12065 0.3048)
			(stroke
				(width 0.1)
				(type default)
			)
			(layer "F.Fab")
		)
		(fp_line
			(start -0.12065 -0.2794)
			(end 0.12065 -0.2794)
			(stroke
				(width 0.1)
				(type default)
			)
			(layer "F.Fab")
		)
		(fp_line
			(start -0.12065 -0.305054)
			(end -0.12065 -0.2794)
			(stroke
				(width 0.1)
				(type default)
			)
			(layer "F.Fab")
		)
		(fp_line
			(start -0.67945 0.3048)
			(end -0.67945 -0.305054)
			(stroke
				(width 0.1)
				(type default)
			)
			(layer "F.Fab")
		)
		(fp_line
			(start -0.67945 -0.305054)
			(end -0.12065 -0.305054)
			(stroke
				(width 0.1)
				(type default)
			)
			(layer "F.Fab")
		)
		(pad "1" smd circle
			(at -0.40005 0 180)
			(size 0 0)
			(layers "F.Cu" "F.Mask" "F.Paste")
			(net "P12V_AUX")
		)
		(pad "2" smd circle
			(at 0.40005 0 180)
			(size 0 0)
			(layers "F.Cu" "F.Mask" "F.Paste")
			(net "P12V_AUX_ADC")
		)
	)
)
